(kicad_pcb
	(version 20241229)
	(generator "pcbnew")
	(generator_version "9.0")
	(general
		(thickness 1.62)
		(legacy_teardrops no)
	)
	(paper "A4")
	(title_block
		(title "OCuLink to 10GbE adapter")
		(date "2026-02-23")
		(rev "1.1.0")
		(company "Antmicro Ltd")
		(comment 1 "www.antmicro.com")
		(comment 9 "footprints 125-129 of 510")
	)
	(layers
		(0 "F.Cu" signal)
		(4 "In1.Cu" signal)
		(6 "In2.Cu" signal)
		(8 "In3.Cu" signal)
		(10 "In4.Cu" signal)
		(12 "In5.Cu" signal)
		(14 "In6.Cu" signal)
		(2 "B.Cu" signal)
		(9 "F.Adhes" user "F.Adhesive")
		(11 "B.Adhes" user "B.Adhesive")
		(13 "F.Paste" user)
		(15 "B.Paste" user)
		(5 "F.SilkS" user "F.Silkscreen")
		(7 "B.SilkS" user "B.Silkscreen")
		(1 "F.Mask" user)
		(3 "B.Mask" user)
		(17 "Dwgs.User" user "User.Drawings")
		(19 "Cmts.User" user "User.Comments")
		(21 "Eco1.User" user "User.Eco1")
		(23 "Eco2.User" user "User.Eco2")
		(25 "Edge.Cuts" user)
		(27 "Margin" user)
		(31 "F.CrtYd" user "F.Courtyard")
		(29 "B.CrtYd" user "B.Courtyard")
		(35 "F.Fab" user)
		(33 "B.Fab" user)
	)
	(footprint "antmicro-footprints:R_0402_1005Metric"
		(layer "F.Cu")
		(at 87.43 58.111999 90)
		(descr "Resistor SMD 0402")
		(tags "resistor SMD 0402")
		(property "Reference" "R27"
			(at -1.160001 2.3 90)
			(layer "F.SilkS")
			(effects
				(font
					(size 0.7 0.7)
					(thickness 0.15)
				)
				(justify left bottom)
			)
		)
		(property "Value" "R_300R_0402"
			(at -1.011843 1.772046 90)
			(layer "F.Fab")
			(hide yes)
			(effects
				(font
					(size 0.7 0.7)
					(thickness 0.15)
				)
				(justify left bottom)
			)
		)
		(property "Datasheet" "https://www.farnell.com/datasheets/3795017.pdf"
			(at 0 0 90)
			(layer "F.Fab")
			(hide yes)
			(effects
				(font
					(size 1.27 1.27)
					(thickness 0.15)
				)
			)
		)
		(property "Description" "MULTICOMP PRO MCMR04X3000FTLSMD Chip Resistor, Ceramic, 300 ohm, ± 1%, 62.5 mW, 0402 [1005 Metric], Thick Film"
			(at 0 0 90)
			(layer "F.Fab")
			(hide yes)
			(effects
				(font
					(size 1.27 1.27)
					(thickness 0.15)
				)
			)
		)
		(property "MPN" "RMCF0402FT300R"
			(at 0 0 90)
			(unlocked yes)
			(layer "F.Fab")
			(hide yes)
			(effects
				(font
					(size 1 1)
					(thickness 0.15)
				)
			)
		)
		(property "Manufacturer" "Stackpole Electronics"
			(at 0 0 90)
			(unlocked yes)
			(layer "F.Fab")
			(hide yes)
			(effects
				(font
					(size 1 1)
					(thickness 0.15)
				)
			)
		)
		(property "License" "Apache-2.0"
			(at 0 0 90)
			(unlocked yes)
			(layer "F.Fab")
			(hide yes)
			(effects
				(font
					(size 1 1)
					(thickness 0.15)
				)
			)
		)
		(property "Author" "Antmicro"
			(at 0 0 90)
			(unlocked yes)
			(layer "F.Fab")
			(hide yes)
			(effects
				(font
					(size 1 1)
					(thickness 0.15)
				)
			)
		)
		(property "Val" "300R"
			(at 0 0 90)
			(unlocked yes)
			(layer "F.Fab")
			(hide yes)
			(effects
				(font
					(size 1 1)
					(thickness 0.15)
				)
			)
		)
		(property "Tolerance" "1%"
			(at 0 0 90)
			(unlocked yes)
			(layer "F.Fab")
			(hide yes)
			(effects
				(font
					(size 1 1)
					(thickness 0.15)
				)
			)
		)
		(sheetname "/Power/")
		(sheetfile "power.kicad_sch")
		(attr smd)
		(fp_rect
			(start -0.925 -0.47)
			(end 0.925 0.47)
			(stroke
				(width 0.05)
				(type default)
			)
			(fill no)
			(layer "F.CrtYd")
		)
		(fp_rect
			(start -0.5 -0.25)
			(end 0.5 0.25)
			(stroke
				(width 0.15)
				(type solid)
			)
			(fill no)
			(layer "F.Fab")
		)
		(pad "1" smd roundrect
			(at -0.48 0 90)
			(size 0.59 0.64)
			(layers "F.Cu" "F.Mask" "F.Paste")
			(roundrect_rratio 0.25)
			(net 28 "GND")
			(pintype "passive")
		)
		(pad "2" smd roundrect
			(at 0.48 0 90)
			(size 0.59 0.64)
			(layers "F.Cu" "F.Mask" "F.Paste")
			(roundrect_rratio 0.25)
			(net 43 "Net-(C37-Pad2)")
			(pintype "passive")
		)
	)
	(footprint "antmicro-footprints:LED_0603_1608Metric_G"
		(layer "F.Cu")
		(at 62.26 52.647 -90)
		(descr "LED SMD 0603 Green")
		(tags "LED SMD 0603 Green")
		(property "Reference" "D2"
			(at -0.607 1.36 90)
			(layer "F.SilkS")
			(effects
				(font
					(size 0.7 0.7)
					(thickness 0.15)
				)
				(justify right top)
			)
		)
		(property "Value" "LED_G_0603_LG_L29K-G2J1-24-Z"
			(at -0.001 1.599 90)
			(layer "F.Fab")
			(hide yes)
			(effects
				(font
					(size 0.7 0.7)
					(thickness 0.15)
				)
				(justify right top)
			)
		)
		(property "Datasheet" "https://look.ams-osram.com/m/19ee86b3ae0ee95b/original/LG-L29K.pdf"
			(at 0 0 90)
			(layer "F.Fab")
			(hide yes)
			(effects
				(font
					(size 1.27 1.27)
					(thickness 0.15)
				)
			)
		)
		(property "Description" "LED, Green, SMD, 0603, 20 mA, 1.7 V, 570 nm"
			(at 0 0 90)
			(layer "F.Fab")
			(hide yes)
			(effects
				(font
					(size 1.27 1.27)
					(thickness 0.15)
				)
			)
		)
		(property "MPN" "LG L29K-G2J1-24-Z"
			(at 0 0 270)
			(unlocked yes)
			(layer "F.Fab")
			(hide yes)
			(effects
				(font
					(size 1 1)
					(thickness 0.15)
				)
			)
		)
		(property "Manufacturer" "OSRAM"
			(at 0 0 270)
			(unlocked yes)
			(layer "F.Fab")
			(hide yes)
			(effects
				(font
					(size 1 1)
					(thickness 0.15)
				)
			)
		)
		(property "Color" "Green"
			(at 0 0 270)
			(unlocked yes)
			(layer "F.Fab")
			(hide yes)
			(effects
				(font
					(size 1 1)
					(thickness 0.15)
				)
			)
		)
		(property "Author" "Antmicro"
			(at 0 0 270)
			(unlocked yes)
			(layer "F.Fab")
			(hide yes)
			(effects
				(font
					(size 1 1)
					(thickness 0.15)
				)
			)
		)
		(property "License" "Apache-2.0"
			(at 0 0 270)
			(unlocked yes)
			(layer "F.Fab")
			(hide yes)
			(effects
				(font
					(size 1 1)
					(thickness 0.15)
				)
			)
		)
		(sheetname "/Power/")
		(sheetfile "power.kicad_sch")
		(attr smd)
		(fp_line
			(start 0.22 0.35)
			(end -0.22 0.35)
			(stroke
				(width 0.15)
				(type solid)
			)
			(layer "F.SilkS")
		)
		(fp_line
			(start -0.094672 0.201008)
			(end -0.094672 -0.198992)
			(stroke
				(width 0.1)
				(type solid)
			)
			(layer "F.SilkS")
		)
		(fp_line
			(start 0.105328 0.201008)
			(end -0.094672 0.001008)
			(stroke
				(width 0.1)
				(type solid)
			)
			(layer "F.SilkS")
		)
		(fp_line
			(start 0.105328 0.201008)
			(end 0.105328 -0.198992)
			(stroke
				(width 0.1)
				(type solid)
			)
			(layer "F.SilkS")
		)
		(fp_line
			(start -0.094672 0.001008)
			(end -0.24 0.001008)
			(stroke
				(width 0.1)
				(type solid)
			)
			(layer "F.SilkS")
		)
		(fp_line
			(start -0.094672 0.001008)
			(end 0.105328 -0.198992)
			(stroke
				(width 0.1)
				(type solid)
			)
			(layer "F.SilkS")
		)
		(fp_line
			(start 0.105328 0.001008)
			(end 0.24 0.001)
			(stroke
				(width 0.1)
				(type solid)
			)
			(layer "F.SilkS")
		)
		(fp_line
			(start -1.18 -0.319)
			(end -1.18 0.321)
			(stroke
				(width 0.15)
				(type solid)
			)
			(layer "F.SilkS")
		)
		(fp_line
			(start 0.22 -0.35)
			(end -0.22 -0.35)
			(stroke
				(width 0.15)
				(type solid)
			)
			(layer "F.SilkS")
		)
		(fp_rect
			(start 1.25 0.65)
			(end -1.25 -0.65)
			(stroke
				(width 0.05)
				(type solid)
			)
			(fill no)
			(layer "F.CrtYd")
		)
		(fp_line
			(start -0.199 0.2)
			(end -0.199 0.1)
			(stroke
				(width 0.15)
				(type solid)
			)
			(layer "F.Fab")
		)
		(fp_line
			(start 0.201 0.2)
			(end 0.201 0)
			(stroke
				(width 0.15)
				(type solid)
			)
			(layer "F.Fab")
		)
		(fp_line
			(start -0.199 0)
			(end -0.597 0)
			(stroke
				(width 0.15)
				(type solid)
			)
			(layer "F.Fab")
		)
		(fp_line
			(start -0.101 0)
			(end 0.201 0.2)
			(stroke
				(width 0.15)
				(type solid)
			)
			(layer "F.Fab")
		)
		(fp_line
			(start 0.201 0)
			(end 0.201 -0.202)
			(stroke
				(width 0.15)
				(type solid)
			)
			(layer "F.Fab")
		)
		(fp_line
			(start 0.599 0)
			(end 0.201 0)
			(stroke
				(width 0.15)
				(type solid)
			)
			(layer "F.Fab")
		)
		(fp_line
			(start -0.199 -0.202)
			(end -0.199 0.1)
			(stroke
				(width 0.15)
				(type solid)
			)
			(layer "F.Fab")
		)
		(fp_line
			(start 0.201 -0.202)
			(end -0.101 0)
			(stroke
				(width 0.15)
				(type solid)
			)
			(layer "F.Fab")
		)
		(fp_rect
			(start 0.848 0.4)
			(end -0.85 -0.402)
			(stroke
				(width 0.15)
				(type solid)
			)
			(fill no)
			(layer "F.Fab")
		)
		(fp_text user "Author: Antmicro"
			(at -1.4224 4.799 270)
			(layer "F.Fab")
			(effects
				(font
					(size 0.7 0.7)
					(thickness 0.15)
				)
				(justify left bottom)
			)
		)
		(fp_text user "License: Apache-2.0"
			(at -1.4224 3.599 270)
			(layer "F.Fab")
			(effects
				(font
					(size 0.7 0.7)
					(thickness 0.15)
				)
				(justify left bottom)
			)
		)
		(fp_text user "${REFERENCE}"
			(at -1.4224 5.999 270)
			(layer "F.Fab")
			(effects
				(font
					(size 0.7 0.7)
					(thickness 0.15)
				)
				(justify left bottom)
			)
		)
		(pad "1" smd roundrect
			(at -0.7 0 90)
			(size 0.8 1)
			(layers "F.Cu" "F.Mask" "F.Paste")
			(roundrect_rratio 0.2)
			(net 28 "GND")
			(pinfunction "C")
			(pintype "passive")
		)
		(pad "2" smd roundrect
			(at 0.7 0 90)
			(size 0.8 1)
			(layers "F.Cu" "F.Mask" "F.Paste")
			(roundrect_rratio 0.2)
			(net 70 "Net-(D2-A)")
			(pinfunction "A")
			(pintype "passive")
		)
	)
	(footprint "antmicro-footprints:C_0603_1608Metric"
		(layer "F.Cu")
		(at 113.2 103.4 -90)
		(descr "Capacitor SMD 0603")
		(tags "capacitor 0603")
		(property "Reference" "C214"
			(at -4.32 -0.71 90)
			(layer "F.SilkS")
			(effects
				(font
					(size 0.7 0.7)
					(thickness 0.15)
				)
				(justify right top)
			)
		)
		(property "Value" "C_10u_10V_X7R_0603"
			(at -1.42757 1.770288 90)
			(layer "F.Fab")
			(hide yes)
			(effects
				(font
					(size 0.7 0.7)
					(thickness 0.15)
				)
				(justify right top)
			)
		)
		(property "Datasheet" "https://www.murata.com/products/productdetail?partno=GRM188Z71A106KA73%23"
			(at 0 0 90)
			(layer "F.Fab")
			(hide yes)
			(effects
				(font
					(size 1.27 1.27)
					(thickness 0.15)
				)
			)
		)
		(property "Description" "SMD Multilayer Ceramic Capacitor,  10µF, 10V, 0603, ±10%, X7R"
			(at 0 0 90)
			(layer "F.Fab")
			(hide yes)
			(effects
				(font
					(size 1.27 1.27)
					(thickness 0.15)
				)
			)
		)
		(property "MPN" "GRM188Z71A106KA73D"
			(at 0 0 270)
			(unlocked yes)
			(layer "F.Fab")
			(hide yes)
			(effects
				(font
					(size 1 1)
					(thickness 0.15)
				)
			)
		)
		(property "Val" "10u"
			(at 0 0 270)
			(unlocked yes)
			(layer "F.Fab")
			(hide yes)
			(effects
				(font
					(size 1 1)
					(thickness 0.15)
				)
			)
		)
		(property "Voltage" "10V"
			(at 0 0 270)
			(unlocked yes)
			(layer "F.Fab")
			(hide yes)
			(effects
				(font
					(size 1 1)
					(thickness 0.15)
				)
			)
		)
		(property "Dielectric" "X7R"
			(at 0 0 270)
			(unlocked yes)
			(layer "F.Fab")
			(hide yes)
			(effects
				(font
					(size 1 1)
					(thickness 0.15)
				)
			)
		)
		(property "Manufacturer" "Murata"
			(at 0 0 270)
			(unlocked yes)
			(layer "F.Fab")
			(hide yes)
			(effects
				(font
					(size 1 1)
					(thickness 0.15)
				)
			)
		)
		(property "License" "Apache-2.0"
			(at 0 0 270)
			(unlocked yes)
			(layer "F.Fab")
			(hide yes)
			(effects
				(font
					(size 1 1)
					(thickness 0.15)
				)
			)
		)
		(property "Author" "Antmicro"
			(at 0 0 270)
			(unlocked yes)
			(layer "F.Fab")
			(hide yes)
			(effects
				(font
					(size 1 1)
					(thickness 0.15)
				)
			)
		)
		(sheetname "/Fan controller/")
		(sheetfile "fan-controller.kicad_sch")
		(attr smd exclude_from_pos_files exclude_from_bom dnp)
		(fp_line
			(start -0.15 0.4)
			(end 0.15 0.4)
			(stroke
				(width 0.15)
				(type solid)
			)
			(layer "F.SilkS")
		)
		(fp_line
			(start -0.15 -0.4)
			(end 0.15 -0.4)
			(stroke
				(width 0.15)
				(type solid)
			)
			(layer "F.SilkS")
		)
		(fp_rect
			(start -1.25 -0.65)
			(end 1.25 0.65)
			(stroke
				(width 0.05)
				(type solid)
			)
			(fill no)
			(layer "F.CrtYd")
		)
		(fp_rect
			(start -0.8 -0.4)
			(end 0.8 0.4)
			(stroke
				(width 0.15)
				(type solid)
			)
			(fill no)
			(layer "F.Fab")
		)
		(pad "1" smd roundrect
			(at -0.7 0 270)
			(size 0.8 1)
			(layers "F.Cu" "F.Mask" "F.Paste")
			(roundrect_rratio 0.2)
			(net 28 "GND")
			(pintype "passive")
		)
		(pad "2" smd roundrect
			(at 0.7 0 270)
			(size 0.8 1)
			(layers "F.Cu" "F.Mask" "F.Paste")
			(roundrect_rratio 0.2)
			(net 388 "/Fan controller/+5V")
			(pintype "passive")
		)
	)
	(footprint "antmicro-footprints:C_0402_1005Metric"
		(layer "F.Cu")
		(at 67.9 100.95 -90)
		(descr "Capacitor SMD 0402")
		(tags "capacitor SMD 0402")
		(property "Reference" "C179"
			(at -1.24 1.5 90)
			(layer "F.SilkS")
			(effects
				(font
					(size 0.7 0.7)
					(thickness 0.15)
				)
				(justify right top)
			)
		)
		(property "Value" "C_100n_0402"
			(at -1.022927 2.155213 90)
			(layer "F.Fab")
			(hide yes)
			(effects
				(font
					(size 0.7 0.7)
					(thickness 0.15)
				)
				(justify right top)
			)
		)
		(property "Datasheet" "https://www.murata.com/products/productdetail?partno=GRM155R61H104KE14%23"
			(at 0 0 90)
			(layer "F.Fab")
			(hide yes)
			(effects
				(font
					(size 1.27 1.27)
					(thickness 0.15)
				)
			)
		)
		(property "Description" "SMD Multilayer Ceramic Capacitor, 0.1 µF, 50 V, 0402 [1005 Metric], ± 10%, X5R, GRM Series"
			(at 0 0 90)
			(layer "F.Fab")
			(hide yes)
			(effects
				(font
					(size 1.27 1.27)
					(thickness 0.15)
				)
			)
		)
		(property "MPN" "GRM155R61H104KE14D"
			(at 0 0 270)
			(unlocked yes)
			(layer "F.Fab")
			(hide yes)
			(effects
				(font
					(size 1 1)
					(thickness 0.15)
				)
			)
		)
		(property "Val" "100n"
			(at 0 0 270)
			(unlocked yes)
			(layer "F.Fab")
			(hide yes)
			(effects
				(font
					(size 1 1)
					(thickness 0.15)
				)
			)
		)
		(property "Voltage" "50V"
			(at 0 0 270)
			(unlocked yes)
			(layer "F.Fab")
			(hide yes)
			(effects
				(font
					(size 1 1)
					(thickness 0.15)
				)
			)
		)
		(property "Dielectric" "X5R"
			(at 0 0 270)
			(unlocked yes)
			(layer "F.Fab")
			(hide yes)
			(effects
				(font
					(size 1 1)
					(thickness 0.15)
				)
			)
		)
		(property "Manufacturer" "Murata"
			(at 0 0 270)
			(unlocked yes)
			(layer "F.Fab")
			(hide yes)
			(effects
				(font
					(size 1 1)
					(thickness 0.15)
				)
			)
		)
		(property "License" "Apache-2.0"
			(at 0 0 270)
			(unlocked yes)
			(layer "F.Fab")
			(hide yes)
			(effects
				(font
					(size 1 1)
					(thickness 0.15)
				)
			)
		)
		(property "Author" "Antmicro"
			(at 0 0 270)
			(unlocked yes)
			(layer "F.Fab")
			(hide yes)
			(effects
				(font
					(size 1 1)
					(thickness 0.15)
				)
			)
		)
		(sheetname "/X710-AT2 power/")
		(sheetfile "x710-at2-power.kicad_sch")
		(attr smd)
		(fp_rect
			(start -0.925 -0.47)
			(end 0.925 0.47)
			(stroke
				(width 0.05)
				(type default)
			)
			(fill no)
			(layer "F.CrtYd")
		)
		(fp_line
			(start -0.494 0.248)
			(end -0.494 -0.25)
			(stroke
				(width 0.15)
				(type solid)
			)
			(layer "F.Fab")
		)
		(fp_line
			(start 0.504 0.248)
			(end -0.494 0.248)
			(stroke
				(width 0.15)
				(type solid)
			)
			(layer "F.Fab")
		)
		(fp_line
			(start -0.494 -0.25)
			(end 0.504 -0.25)
			(stroke
				(width 0.15)
				(type solid)
			)
			(layer "F.Fab")
		)
		(fp_line
			(start 0.504 -0.25)
			(end 0.504 0.248)
			(stroke
				(width 0.15)
				(type solid)
			)
			(layer "F.Fab")
		)
		(pad "1" smd roundrect
			(at -0.48 0 270)
			(size 0.59 0.64)
			(layers "F.Cu" "F.Mask" "F.Paste")
			(roundrect_rratio 0.25)
			(net 28 "GND")
			(pintype "passive")
		)
		(pad "2" smd roundrect
			(at 0.48 0 270)
			(size 0.59 0.64)
			(layers "F.Cu" "F.Mask" "F.Paste")
			(roundrect_rratio 0.25)
			(net 302 "+1V0")
			(pintype "passive")
		)
	)
	(footprint "antmicro-footprints:C_0402_1005Metric"
		(layer "F.Cu")
		(at 103.498001 62.778655 -90)
		(descr "Capacitor SMD 0402")
		(tags "capacitor SMD 0402")
		(property "Reference" "C191"
			(at 1.406345 -2.351999 270)
			(layer "F.SilkS")
			(effects
				(font
					(size 0.7 0.7)
					(thickness 0.15)
				)
				(justify left bottom)
			)
		)
		(property "Value" "C_220n_16V_0402"
			(at -1.022927 2.155213 270)
			(layer "F.Fab")
			(hide yes)
			(effects
				(font
					(size 0.7 0.7)
					(thickness 0.15)
				)
				(justify left bottom)
			)
		)
		(property "Datasheet" "https://www.murata.com/products/productdetail?partno=GRM155R71C224KA12%23"
			(at 0 0 270)
			(layer "F.Fab")
			(hide yes)
			(effects
				(font
					(size 1.27 1.27)
					(thickness 0.15)
				)
			)
		)
		(property "Description" "SMD Multilayer Ceramic Capacitor, 0.22 µF, 16 V, 0402 [1005 Metric], ± 10%, X7R, GRM Series"
			(at 0 0 270)
			(layer "F.Fab")
			(hide yes)
			(effects
				(font
					(size 1.27 1.27)
					(thickness 0.15)
				)
			)
		)
		(property "MPN" "GRM155R71C224KA12D"
			(at 0 0 270)
			(unlocked yes)
			(layer "F.Fab")
			(hide yes)
			(effects
				(font
					(size 1 1)
					(thickness 0.15)
				)
			)
		)
		(property "Manufacturer" "Murata"
			(at 0 0 270)
			(unlocked yes)
			(layer "F.Fab")
			(hide yes)
			(effects
				(font
					(size 1 1)
					(thickness 0.15)
				)
			)
		)
		(property "License" "Apache-2.0"
			(at 0 0 270)
			(unlocked yes)
			(layer "F.Fab")
			(hide yes)
			(effects
				(font
					(size 1 1)
					(thickness 0.15)
				)
			)
		)
		(property "Author" "Antmicro"
			(at 0 0 270)
			(unlocked yes)
			(layer "F.Fab")
			(hide yes)
			(effects
				(font
					(size 1 1)
					(thickness 0.15)
				)
			)
		)
		(property "Val" "220n"
			(at 0 0 270)
			(unlocked yes)
			(layer "F.Fab")
			(hide yes)
			(effects
				(font
					(size 1 1)
					(thickness 0.15)
				)
			)
		)
		(property "Voltage" "16V"
			(at 0 0 270)
			(unlocked yes)
			(layer "F.Fab")
			(hide yes)
			(effects
				(font
					(size 1 1)
					(thickness 0.15)
				)
			)
		)
		(property "Dielectric" "X7R"
			(at 0 0 270)
			(unlocked yes)
			(layer "F.Fab")
			(hide yes)
			(effects
				(font
					(size 1 1)
					(thickness 0.15)
				)
			)
		)
		(sheetname "/X710-AT2 PCIe/")
		(sheetfile "x710-at2-pcie.kicad_sch")
		(attr smd)
		(fp_rect
			(start -0.925 -0.47)
			(end 0.925 0.47)
			(stroke
				(width 0.05)
				(type default)
			)
			(fill no)
			(layer "F.CrtYd")
		)
		(fp_line
			(start -0.494 0.248)
			(end -0.494 -0.25)
			(stroke
				(width 0.15)
				(type solid)
			)
			(layer "F.Fab")
		)
		(fp_line
			(start 0.504 0.248)
			(end -0.494 0.248)
			(stroke
				(width 0.15)
				(type solid)
			)
			(layer "F.Fab")
		)
		(fp_line
			(start -0.494 -0.25)
			(end 0.504 -0.25)
			(stroke
				(width 0.15)
				(type solid)
			)
			(layer "F.Fab")
		)
		(fp_line
			(start 0.504 -0.25)
			(end 0.504 0.248)
			(stroke
				(width 0.15)
				(type solid)
			)
			(layer "F.Fab")
		)
		(pad "1" smd roundrect
			(at -0.48 0 270)
			(size 0.59 0.64)
			(layers "F.Cu" "F.Mask" "F.Paste")
			(roundrect_rratio 0.25)
			(net 17 "/OCuLink/PCIe_{x4}.TX0-")
			(pintype "passive")
		)
		(pad "2" smd roundrect
			(at 0.48 0 270)
			(size 0.59 0.64)
			(layers "F.Cu" "F.Mask" "F.Paste")
			(roundrect_rratio 0.25)
			(net 33 "/X710-AT2 PCIe/PCIe_{x4}_AC.TX0-")
			(pintype "passive")
		)
	)
)
